(kicad_pcb
	(version 20260206)
	(generator "pcbnew")
	(generator_version "10.0")
	(general
		(thickness 1.6)
		(legacy_teardrops no)
	)
	(paper "A4")
	(title_block
		(title "01162023_DA0F0TEBIF0_F0T_Expander_BD_F_brd_V02_OCP.brd")
		(comment 1 "Grand Teton / footprints 512-518 of 9728")
	)
	(layers
		(0 "F.Cu" signal "TOP")
		(4 "In1.Cu" signal "GND")
		(6 "In2.Cu" signal "VCC")
		(8 "In3.Cu" signal "VCC1")
		(10 "In4.Cu" signal "GND1")
		(12 "In5.Cu" signal "IN1")
		(14 "In6.Cu" signal "GND2")
		(16 "In7.Cu" signal "IN2")
		(18 "In8.Cu" signal "GND3")
		(20 "In9.Cu" signal "IN3")
		(22 "In10.Cu" signal "GND4")
		(24 "In11.Cu" signal "IN4")
		(26 "In12.Cu" signal "GND5")
		(28 "In13.Cu" signal "IN5")
		(30 "In14.Cu" signal "GND6")
		(32 "In15.Cu" signal "IN6")
		(34 "In16.Cu" signal "GND7")
		(2 "B.Cu" signal "BOTTOM")
		(9 "F.Adhes" user "F.Adhesive")
		(11 "B.Adhes" user "B.Adhesive")
		(13 "F.Paste" user "Package Geometry/Pastemask Top")
		(15 "B.Paste" user "Package Geometry/Pastemask Bottom")
		(5 "F.SilkS" user "Ref Des/Silkscreen Top")
		(7 "B.SilkS" user "Ref Des/Silkscreen Bottom")
		(1 "F.Mask" user "Board Geometry/Soldermask Top")
		(3 "B.Mask" user "Board Geometry/Soldermask Bottom")
		(17 "Dwgs.User" user "User.Drawings")
		(19 "Cmts.User" user "User.Comments")
		(21 "Eco1.User" user "User.Eco1")
		(23 "Eco2.User" user "User.Eco2")
		(25 "Edge.Cuts" user "Board Geometry/Outline")
		(27 "Margin" user)
		(31 "F.CrtYd" user "Package Geometry/Place Bound Top")
		(29 "B.CrtYd" user "Package Geometry/Place Bound Bottom")
		(35 "F.Fab" user "Ref Des/Assembly Top")
		(33 "B.Fab" user "Ref Des/Assembly Bottom")
	)
	(footprint ""
		(layer "F.Cu")
		(at 5.081524 -251.312426 -90)
		(property "Reference" "C4242"
			(at 0 0 270)
			(layer "F.SilkS")
			(hide yes)
			(effects
				(font
					(size 1.27 1.27)
				)
			)
		)
		(property "Value" ""
			(at 0 0 270)
			(layer "F.Fab")
			(effects
				(font
					(size 1.27 1.27)
				)
			)
		)
		(duplicate_pad_numbers_are_jumpers no)
		(fp_line
			(start -1.2954 0.5842)
			(end -1.2954 -0.5842)
			(stroke
				(width 0.1524)
				(type default)
			)
			(layer "F.SilkS")
		)
		(fp_line
			(start 1.2954 0.5842)
			(end -1.2954 0.5842)
			(stroke
				(width 0.1524)
				(type default)
			)
			(layer "F.SilkS")
		)
		(fp_line
			(start -1.2954 -0.5842)
			(end 1.2954 -0.5842)
			(stroke
				(width 0.1524)
				(type default)
			)
			(layer "F.SilkS")
		)
		(fp_line
			(start 1.2954 -0.5842)
			(end 1.2954 0.5842)
			(stroke
				(width 0.1524)
				(type default)
			)
			(layer "F.SilkS")
		)
		(fp_line
			(start -0.8636 0.4572)
			(end -0.8636 0.4064)
			(stroke
				(width 0.1)
				(type default)
			)
			(layer "F.Fab")
		)
		(fp_line
			(start 0.8636 0.4572)
			(end -0.8636 0.4572)
			(stroke
				(width 0.1)
				(type default)
			)
			(layer "F.Fab")
		)
		(fp_line
			(start -1.1938 0.4064)
			(end -1.1938 -0.4064)
			(stroke
				(width 0.1)
				(type default)
			)
			(layer "F.Fab")
		)
		(fp_line
			(start -0.8636 0.4064)
			(end -1.1938 0.4064)
			(stroke
				(width 0.1)
				(type default)
			)
			(layer "F.Fab")
		)
		(fp_line
			(start 0.8636 0.4064)
			(end 0.8636 0.4572)
			(stroke
				(width 0.1)
				(type default)
			)
			(layer "F.Fab")
		)
		(fp_line
			(start 1.1938 0.4064)
			(end 0.8636 0.4064)
			(stroke
				(width 0.1)
				(type default)
			)
			(layer "F.Fab")
		)
		(fp_line
			(start -1.1938 -0.4064)
			(end -0.8636 -0.4064)
			(stroke
				(width 0.1)
				(type default)
			)
			(layer "F.Fab")
		)
		(fp_line
			(start -0.8636 -0.4064)
			(end -0.8636 -0.4572)
			(stroke
				(width 0.1)
				(type default)
			)
			(layer "F.Fab")
		)
		(fp_line
			(start 0.8636 -0.4064)
			(end 1.1938 -0.4064)
			(stroke
				(width 0.1)
				(type default)
			)
			(layer "F.Fab")
		)
		(fp_line
			(start 1.1938 -0.4064)
			(end 1.1938 0.4064)
			(stroke
				(width 0.1)
				(type default)
			)
			(layer "F.Fab")
		)
		(fp_line
			(start -0.8636 -0.4572)
			(end 0.8636 -0.4572)
			(stroke
				(width 0.1)
				(type default)
			)
			(layer "F.Fab")
		)
		(fp_line
			(start 0.8636 -0.4572)
			(end 0.8636 -0.4064)
			(stroke
				(width 0.1)
				(type default)
			)
			(layer "F.Fab")
		)
		(pad "1" smd rect
			(at -0.7366 0 180)
			(size 0.7112 0.8128)
			(layers "F.Cu" "F.Mask" "F.Paste")
			(net "P1V25_SERDES_VDDPLL_PEX0_C8")
		)
		(pad "2" smd rect
			(at 0.7366 0 180)
			(size 0.7112 0.8128)
			(layers "F.Cu" "F.Mask" "F.Paste")
			(net "GND")
		)
	)
	(footprint ""
		(layer "F.Cu")
		(at 219.202 -201.168)
		(property "Reference" "R1517"
			(at 0 0 0)
			(layer "F.SilkS")
			(hide yes)
			(effects
				(font
					(size 1.27 1.27)
				)
			)
		)
		(property "Value" ""
			(at 0 0 0)
			(layer "F.Fab")
			(effects
				(font
					(size 1.27 1.27)
				)
			)
		)
		(duplicate_pad_numbers_are_jumpers no)
		(fp_line
			(start -0.7874 -0.4064)
			(end 0.7874 -0.4064)
			(stroke
				(width 0.1524)
				(type default)
			)
			(layer "F.SilkS")
		)
		(fp_line
			(start -0.7874 0.4064)
			(end -0.7874 -0.4064)
			(stroke
				(width 0.1524)
				(type default)
			)
			(layer "F.SilkS")
		)
		(fp_line
			(start 0.7874 -0.4064)
			(end 0.7874 0.4064)
			(stroke
				(width 0.1524)
				(type default)
			)
			(layer "F.SilkS")
		)
		(fp_line
			(start 0.7874 0.4064)
			(end -0.7874 0.4064)
			(stroke
				(width 0.1524)
				(type default)
			)
			(layer "F.SilkS")
		)
		(fp_line
			(start -0.67945 -0.305054)
			(end -0.12065 -0.305054)
			(stroke
				(width 0.1)
				(type default)
			)
			(layer "F.Fab")
		)
		(fp_line
			(start -0.67945 0.3048)
			(end -0.67945 -0.305054)
			(stroke
				(width 0.1)
				(type default)
			)
			(layer "F.Fab")
		)
		(fp_line
			(start -0.12065 -0.305054)
			(end -0.12065 -0.2794)
			(stroke
				(width 0.1)
				(type default)
			)
			(layer "F.Fab")
		)
		(fp_line
			(start -0.12065 -0.2794)
			(end 0.12065 -0.2794)
			(stroke
				(width 0.1)
				(type default)
			)
			(layer "F.Fab")
		)
		(fp_line
			(start -0.12065 0.2794)
			(end -0.12065 0.3048)
			(stroke
				(width 0.1)
				(type default)
			)
			(layer "F.Fab")
		)
		(fp_line
			(start -0.12065 0.3048)
			(end -0.67945 0.3048)
			(stroke
				(width 0.1)
				(type default)
			)
			(layer "F.Fab")
		)
		(fp_line
			(start 0.120396 0.2794)
			(end -0.12065 0.2794)
			(stroke
				(width 0.1)
				(type default)
			)
			(layer "F.Fab")
		)
		(fp_line
			(start 0.120396 0.3048)
			(end 0.120396 0.2794)
			(stroke
				(width 0.1)
				(type default)
			)
			(layer "F.Fab")
		)
		(fp_line
			(start 0.12065 -0.3048)
			(end 0.67945 -0.3048)
			(stroke
				(width 0.1)
				(type default)
			)
			(layer "F.Fab")
		)
		(fp_line
			(start 0.12065 -0.2794)
			(end 0.12065 -0.3048)
			(stroke
				(width 0.1)
				(type default)
			)
			(layer "F.Fab")
		)
		(fp_line
			(start 0.67945 -0.3048)
			(end 0.67945 0.3048)
			(stroke
				(width 0.1)
				(type default)
			)
			(layer "F.Fab")
		)
		(fp_line
			(start 0.67945 0.3048)
			(end 0.120396 0.3048)
			(stroke
				(width 0.1)
				(type default)
			)
			(layer "F.Fab")
		)
		(pad "1" smd circle
			(at -0.40005 0)
			(size 0 0)
			(layers "F.Cu" "F.Mask" "F.Paste")
			(net "SMB_NIC5_LS_EN")
		)
		(pad "2" smd circle
			(at 0.40005 0)
			(size 0 0)
			(layers "F.Cu" "F.Mask" "F.Paste")
			(net "P3V3_NIC5")
		)
	)
	(footprint ""
		(layer "F.Cu")
		(at 46.255178 -35.876738)
		(property "Reference" "R5880"
			(at 0 0 0)
			(layer "F.SilkS")
			(hide yes)
			(effects
				(font
					(size 1.27 1.27)
				)
			)
		)
		(property "Value" ""
			(at 0 0 0)
			(layer "F.Fab")
			(effects
				(font
					(size 1.27 1.27)
				)
			)
		)
		(duplicate_pad_numbers_are_jumpers no)
		(fp_line
			(start -0.7874 -0.4064)
			(end 0.7874 -0.4064)
			(stroke
				(width 0.1524)
				(type default)
			)
			(layer "F.SilkS")
		)
		(fp_line
			(start -0.7874 0.4064)
			(end -0.7874 -0.4064)
			(stroke
				(width 0.1524)
				(type default)
			)
			(layer "F.SilkS")
		)
		(fp_line
			(start 0.7874 -0.4064)
			(end 0.7874 0.4064)
			(stroke
				(width 0.1524)
				(type default)
			)
			(layer "F.SilkS")
		)
		(fp_line
			(start 0.7874 0.4064)
			(end -0.7874 0.4064)
			(stroke
				(width 0.1524)
				(type default)
			)
			(layer "F.SilkS")
		)
		(fp_line
			(start -0.67945 -0.305054)
			(end -0.12065 -0.305054)
			(stroke
				(width 0.1)
				(type default)
			)
			(layer "F.Fab")
		)
		(fp_line
			(start -0.67945 0.3048)
			(end -0.67945 -0.305054)
			(stroke
				(width 0.1)
				(type default)
			)
			(layer "F.Fab")
		)
		(fp_line
			(start -0.12065 -0.305054)
			(end -0.12065 -0.2794)
			(stroke
				(width 0.1)
				(type default)
			)
			(layer "F.Fab")
		)
		(fp_line
			(start -0.12065 -0.2794)
			(end 0.12065 -0.2794)
			(stroke
				(width 0.1)
				(type default)
			)
			(layer "F.Fab")
		)
		(fp_line
			(start -0.12065 0.2794)
			(end -0.12065 0.3048)
			(stroke
				(width 0.1)
				(type default)
			)
			(layer "F.Fab")
		)
		(fp_line
			(start -0.12065 0.3048)
			(end -0.67945 0.3048)
			(stroke
				(width 0.1)
				(type default)
			)
			(layer "F.Fab")
		)
		(fp_line
			(start 0.120396 0.2794)
			(end -0.12065 0.2794)
			(stroke
				(width 0.1)
				(type default)
			)
			(layer "F.Fab")
		)
		(fp_line
			(start 0.120396 0.3048)
			(end 0.120396 0.2794)
			(stroke
				(width 0.1)
				(type default)
			)
			(layer "F.Fab")
		)
		(fp_line
			(start 0.12065 -0.3048)
			(end 0.67945 -0.3048)
			(stroke
				(width 0.1)
				(type default)
			)
			(layer "F.Fab")
		)
		(fp_line
			(start 0.12065 -0.2794)
			(end 0.12065 -0.3048)
			(stroke
				(width 0.1)
				(type default)
			)
			(layer "F.Fab")
		)
		(fp_line
			(start 0.67945 -0.3048)
			(end 0.67945 0.3048)
			(stroke
				(width 0.1)
				(type default)
			)
			(layer "F.Fab")
		)
		(fp_line
			(start 0.67945 0.3048)
			(end 0.120396 0.3048)
			(stroke
				(width 0.1)
				(type default)
			)
			(layer "F.Fab")
		)
		(pad "1" smd circle
			(at -0.40005 0)
			(size 0 0)
			(layers "F.Cu" "F.Mask" "F.Paste")
			(net "P3V3_AUX")
		)
		(pad "2" smd circle
			(at 0.40005 0)
			(size 0 0)
			(layers "F.Cu" "F.Mask" "F.Paste")
			(net "PWRGD_P3V3_SSD2_D")
		)
	)
	(footprint ""
		(layer "F.Cu")
		(at 36.638484 -134.008876)
		(property "Reference" "C35"
			(at 0 0 0)
			(layer "F.SilkS")
			(hide yes)
			(effects
				(font
					(size 1.27 1.27)
				)
			)
		)
		(property "Value" ""
			(at 0 0 0)
			(layer "F.Fab")
			(effects
				(font
					(size 1.27 1.27)
				)
			)
		)
		(duplicate_pad_numbers_are_jumpers no)
		(fp_line
			(start -0.299974 -0.150114)
			(end 0.299974 -0.150114)
			(stroke
				(width 0.1)
				(type default)
			)
			(layer "F.Fab")
		)
		(fp_line
			(start -0.299974 0.150114)
			(end -0.299974 -0.150114)
			(stroke
				(width 0.1)
				(type default)
			)
			(layer "F.Fab")
		)
		(fp_line
			(start 0.299974 -0.150114)
			(end 0.299974 0.150114)
			(stroke
				(width 0.1)
				(type default)
			)
			(layer "F.Fab")
		)
		(fp_line
			(start 0.299974 0.150114)
			(end -0.299974 0.150114)
			(stroke
				(width 0.1)
				(type default)
			)
			(layer "F.Fab")
		)
		(pad "1" smd rect
			(at -0.2667 0)
			(size 0.3048 0.381)
			(layers "F.Cu" "F.Mask" "F.Paste")
			(net "P5E_PEX0_STN1_TX_DP<30>")
		)
		(pad "2" smd rect
			(at 0.2667 0)
			(size 0.3048 0.381)
			(layers "F.Cu" "F.Mask" "F.Paste")
			(net "P5E_PEX0_STN1_TX_C_DP<30>")
		)
	)
	(footprint ""
		(layer "F.Cu")
		(at 16.785336 -271.184624)
		(property "Reference" "R771"
			(at 0 0 0)
			(layer "F.SilkS")
			(hide yes)
			(effects
				(font
					(size 1.27 1.27)
				)
			)
		)
		(property "Value" ""
			(at 0 0 0)
			(layer "F.Fab")
			(effects
				(font
					(size 1.27 1.27)
				)
			)
		)
		(duplicate_pad_numbers_are_jumpers no)
		(fp_line
			(start -0.7874 -0.4064)
			(end 0.7874 -0.4064)
			(stroke
				(width 0.1524)
				(type default)
			)
			(layer "F.SilkS")
		)
		(fp_line
			(start -0.7874 0.4064)
			(end -0.7874 -0.4064)
			(stroke
				(width 0.1524)
				(type default)
			)
			(layer "F.SilkS")
		)
		(fp_line
			(start 0.7874 -0.4064)
			(end 0.7874 0.4064)
			(stroke
				(width 0.1524)
				(type default)
			)
			(layer "F.SilkS")
		)
		(fp_line
			(start 0.7874 0.4064)
			(end -0.7874 0.4064)
			(stroke
				(width 0.1524)
				(type default)
			)
			(layer "F.SilkS")
		)
		(fp_line
			(start -0.67945 -0.305054)
			(end -0.12065 -0.305054)
			(stroke
				(width 0.1)
				(type default)
			)
			(layer "F.Fab")
		)
		(fp_line
			(start -0.67945 0.3048)
			(end -0.67945 -0.305054)
			(stroke
				(width 0.1)
				(type default)
			)
			(layer "F.Fab")
		)
		(fp_line
			(start -0.12065 -0.305054)
			(end -0.12065 -0.2794)
			(stroke
				(width 0.1)
				(type default)
			)
			(layer "F.Fab")
		)
		(fp_line
			(start -0.12065 -0.2794)
			(end 0.12065 -0.2794)
			(stroke
				(width 0.1)
				(type default)
			)
			(layer "F.Fab")
		)
		(fp_line
			(start -0.12065 0.2794)
			(end -0.12065 0.3048)
			(stroke
				(width 0.1)
				(type default)
			)
			(layer "F.Fab")
		)
		(fp_line
			(start -0.12065 0.3048)
			(end -0.67945 0.3048)
			(stroke
				(width 0.1)
				(type default)
			)
			(layer "F.Fab")
		)
		(fp_line
			(start 0.120396 0.2794)
			(end -0.12065 0.2794)
			(stroke
				(width 0.1)
				(type default)
			)
			(layer "F.Fab")
		)
		(fp_line
			(start 0.120396 0.3048)
			(end 0.120396 0.2794)
			(stroke
				(width 0.1)
				(type default)
			)
			(layer "F.Fab")
		)
		(fp_line
			(start 0.12065 -0.3048)
			(end 0.67945 -0.3048)
			(stroke
				(width 0.1)
				(type default)
			)
			(layer "F.Fab")
		)
		(fp_line
			(start 0.12065 -0.2794)
			(end 0.12065 -0.3048)
			(stroke
				(width 0.1)
				(type default)
			)
			(layer "F.Fab")
		)
		(fp_line
			(start 0.67945 -0.3048)
			(end 0.67945 0.3048)
			(stroke
				(width 0.1)
				(type default)
			)
			(layer "F.Fab")
		)
		(fp_line
			(start 0.67945 0.3048)
			(end 0.120396 0.3048)
			(stroke
				(width 0.1)
				(type default)
			)
			(layer "F.Fab")
		)
		(pad "1" smd circle
			(at -0.40005 0)
			(size 0 0)
			(layers "F.Cu" "F.Mask" "F.Paste")
			(net "PEX0_P1V25_ADC_A1")
		)
		(pad "2" smd circle
			(at 0.40005 0)
			(size 0 0)
			(layers "F.Cu" "F.Mask" "F.Paste")
			(net "P3V3_AUX")
		)
	)
	(footprint ""
		(layer "F.Cu")
		(at 173.854364 -48.21809)
		(property "Reference" "PD64"
			(at -3.471164 2.24536 0)
			(unlocked yes)
			(layer "F.SilkS")
			(effects
				(font
					(size 0.7874 0.5842)
					(thickness 0.1524)
				)
				(justify left)
			)
		)
		(property "Value" ""
			(at 0 0 0)
			(layer "F.Fab")
			(effects
				(font
					(size 1.27 1.27)
				)
			)
		)
		(duplicate_pad_numbers_are_jumpers no)
		(fp_line
			(start -3.400044 -1.459992)
			(end 4.107942 -1.459992)
			(stroke
				(width 0.1524)
				(type default)
			)
			(layer "F.SilkS")
		)
		(fp_line
			(start -3.400044 1.459992)
			(end -3.400044 -1.459992)
			(stroke
				(width 0.1524)
				(type default)
			)
			(layer "F.SilkS")
		)
		(fp_line
			(start 4.107942 -1.459992)
			(end 4.107942 1.459992)
			(stroke
				(width 0.1524)
				(type default)
			)
			(layer "F.SilkS")
		)
		(fp_line
			(start 4.107942 1.459992)
			(end -3.400044 1.459992)
			(stroke
				(width 0.1524)
				(type default)
			)
			(layer "F.SilkS")
		)
		(fp_poly
			(pts
				(xy 4.107942 -1.459992) (xy 4.107942 1.459992) (xy 3.308096 1.459992) (xy 3.308096 -1.459992)
			)
			(stroke
				(width 0)
				(type default)
			)
			(fill yes)
			(layer "F.SilkS")
		)
		(fp_line
			(start -2.29997 -1.459992)
			(end 2.29997 -1.459992)
			(stroke
				(width 0.1)
				(type default)
			)
			(layer "F.Fab")
		)
		(fp_line
			(start -2.29997 1.459992)
			(end -2.29997 -1.459992)
			(stroke
				(width 0.1)
				(type default)
			)
			(layer "F.Fab")
		)
		(fp_line
			(start 2.29997 -1.459992)
			(end 2.29997 1.459992)
			(stroke
				(width 0.1)
				(type default)
			)
			(layer "F.Fab")
		)
		(fp_line
			(start 2.29997 1.459992)
			(end -2.29997 1.459992)
			(stroke
				(width 0.1)
				(type default)
			)
			(layer "F.Fab")
		)
		(fp_text user "+"
			(at -4.7752 -0.12065 0)
			(unlocked yes)
			(layer "F.SilkS")
			(effects
				(font
					(size 1.905 1.4224)
					(thickness 0.1524)
				)
				(justify left)
			)
		)
		(fp_text user "-"
			(at 5.4102 0.29845 180)
			(unlocked yes)
			(layer "F.SilkS")
			(effects
				(font
					(size 1.905 1.4224)
					(thickness 0.1524)
				)
				(justify left)
			)
		)
		(fp_text user "+"
			(at -4.7752 -0.12065 0)
			(unlocked yes)
			(layer "F.Fab")
			(effects
				(font
					(size 1.905 1.4224)
					(thickness 0.1524)
				)
				(justify left)
			)
		)
		(fp_text user "-"
			(at 5.4102 0.29845 180)
			(unlocked yes)
			(layer "F.Fab")
			(effects
				(font
					(size 1.905 1.4224)
					(thickness 0.1524)
				)
				(justify left)
			)
		)
		(pad "A" smd rect
			(at -1.999996 0 90)
			(size 1.7018 2.5146)
			(layers "F.Cu" "F.Mask" "F.Paste")
			(net "GND")
		)
		(pad "C" smd rect
			(at 1.999996 0 90)
			(size 1.7018 2.5146)
			(layers "F.Cu" "F.Mask" "F.Paste")
			(net "P3V3_SSD6")
		)
	)
	(footprint ""
		(layer "F.Cu")
		(at 123.67514 -91.462606)
		(property "Reference" "R1585"
			(at 0 0 0)
			(layer "F.SilkS")
			(hide yes)
			(effects
				(font
					(size 1.27 1.27)
				)
			)
		)
		(property "Value" ""
			(at 0 0 0)
			(layer "F.Fab")
			(effects
				(font
					(size 1.27 1.27)
				)
			)
		)
		(duplicate_pad_numbers_are_jumpers no)
		(fp_line
			(start -0.7874 -0.4064)
			(end 0.7874 -0.4064)
			(stroke
				(width 0.1524)
				(type default)
			)
			(layer "F.SilkS")
		)
		(fp_line
			(start -0.7874 0.4064)
			(end -0.7874 -0.4064)
			(stroke
				(width 0.1524)
				(type default)
			)
			(layer "F.SilkS")
		)
		(fp_line
			(start 0.7874 -0.4064)
			(end 0.7874 0.4064)
			(stroke
				(width 0.1524)
				(type default)
			)
			(layer "F.SilkS")
		)
		(fp_line
			(start 0.7874 0.4064)
			(end -0.7874 0.4064)
			(stroke
				(width 0.1524)
				(type default)
			)
			(layer "F.SilkS")
		)
		(fp_line
			(start -0.67945 -0.305054)
			(end -0.12065 -0.305054)
			(stroke
				(width 0.1)
				(type default)
			)
			(layer "F.Fab")
		)
		(fp_line
			(start -0.67945 0.3048)
			(end -0.67945 -0.305054)
			(stroke
				(width 0.1)
				(type default)
			)
			(layer "F.Fab")
		)
		(fp_line
			(start -0.12065 -0.305054)
			(end -0.12065 -0.2794)
			(stroke
				(width 0.1)
				(type default)
			)
			(layer "F.Fab")
		)
		(fp_line
			(start -0.12065 -0.2794)
			(end 0.12065 -0.2794)
			(stroke
				(width 0.1)
				(type default)
			)
			(layer "F.Fab")
		)
		(fp_line
			(start -0.12065 0.2794)
			(end -0.12065 0.3048)
			(stroke
				(width 0.1)
				(type default)
			)
			(layer "F.Fab")
		)
		(fp_line
			(start -0.12065 0.3048)
			(end -0.67945 0.3048)
			(stroke
				(width 0.1)
				(type default)
			)
			(layer "F.Fab")
		)
		(fp_line
			(start 0.120396 0.2794)
			(end -0.12065 0.2794)
			(stroke
				(width 0.1)
				(type default)
			)
			(layer "F.Fab")
		)
		(fp_line
			(start 0.120396 0.3048)
			(end 0.120396 0.2794)
			(stroke
				(width 0.1)
				(type default)
			)
			(layer "F.Fab")
		)
		(fp_line
			(start 0.12065 -0.3048)
			(end 0.67945 -0.3048)
			(stroke
				(width 0.1)
				(type default)
			)
			(layer "F.Fab")
		)
		(fp_line
			(start 0.12065 -0.2794)
			(end 0.12065 -0.3048)
			(stroke
				(width 0.1)
				(type default)
			)
			(layer "F.Fab")
		)
		(fp_line
			(start 0.67945 -0.3048)
			(end 0.67945 0.3048)
			(stroke
				(width 0.1)
				(type default)
			)
			(layer "F.Fab")
		)
		(fp_line
			(start 0.67945 0.3048)
			(end 0.120396 0.3048)
			(stroke
				(width 0.1)
				(type default)
			)
			(layer "F.Fab")
		)
		(pad "1" smd circle
			(at -0.40005 0)
			(size 0 0)
			(layers "F.Cu" "F.Mask" "F.Paste")
			(net "SMB_BIC_I2C9_MUX0_SSD2_R_SCL")
		)
		(pad "2" smd circle
			(at 0.40005 0)
			(size 0 0)
			(layers "F.Cu" "F.Mask" "F.Paste")
			(net "SMB_BIC_I2C9_MUX0_SSD2_SCL")
		)
	)
)
